(kicad_pcb
	(version 20260206)
	(generator "pcbnew")
	(generator_version "10.0")
	(general
		(thickness 1.6)
		(legacy_teardrops no)
	)
	(paper "A4")
	(title_block
		(title "01162023_DA0F0TEBIF0_F0T_Expander_BD_F_brd_V02_OCP.brd")
		(comment 1 "Grand Teton / footprints 1162-1167 of 9728")
	)
	(layers
		(0 "F.Cu" signal "TOP")
		(4 "In1.Cu" signal "GND")
		(6 "In2.Cu" signal "VCC")
		(8 "In3.Cu" signal "VCC1")
		(10 "In4.Cu" signal "GND1")
		(12 "In5.Cu" signal "IN1")
		(14 "In6.Cu" signal "GND2")
		(16 "In7.Cu" signal "IN2")
		(18 "In8.Cu" signal "GND3")
		(20 "In9.Cu" signal "IN3")
		(22 "In10.Cu" signal "GND4")
		(24 "In11.Cu" signal "IN4")
		(26 "In12.Cu" signal "GND5")
		(28 "In13.Cu" signal "IN5")
		(30 "In14.Cu" signal "GND6")
		(32 "In15.Cu" signal "IN6")
		(34 "In16.Cu" signal "GND7")
		(2 "B.Cu" signal "BOTTOM")
		(9 "F.Adhes" user "F.Adhesive")
		(11 "B.Adhes" user "B.Adhesive")
		(13 "F.Paste" user "Package Geometry/Pastemask Top")
		(15 "B.Paste" user "Package Geometry/Pastemask Bottom")
		(5 "F.SilkS" user "Ref Des/Silkscreen Top")
		(7 "B.SilkS" user "Ref Des/Silkscreen Bottom")
		(1 "F.Mask" user "Board Geometry/Soldermask Top")
		(3 "B.Mask" user "Board Geometry/Soldermask Bottom")
		(17 "Dwgs.User" user "User.Drawings")
		(19 "Cmts.User" user "User.Comments")
		(21 "Eco1.User" user "User.Eco1")
		(23 "Eco2.User" user "User.Eco2")
		(25 "Edge.Cuts" user "Board Geometry/Outline")
		(27 "Margin" user)
		(31 "F.CrtYd" user "Package Geometry/Place Bound Top")
		(29 "B.CrtYd" user "Package Geometry/Place Bound Bottom")
		(35 "F.Fab" user "Ref Des/Assembly Top")
		(33 "B.Fab" user "Ref Des/Assembly Bottom")
	)
	(footprint ""
		(layer "F.Cu")
		(at 33.287716 -288.419032)
		(property "Reference" "C3055"
			(at 0 0 0)
			(layer "F.SilkS")
			(hide yes)
			(effects
				(font
					(size 1.27 1.27)
				)
			)
		)
		(property "Value" ""
			(at 0 0 0)
			(layer "F.Fab")
			(effects
				(font
					(size 1.27 1.27)
				)
			)
		)
		(duplicate_pad_numbers_are_jumpers no)
		(fp_line
			(start -1.2954 -0.5842)
			(end 1.2954 -0.5842)
			(stroke
				(width 0.1524)
				(type default)
			)
			(layer "F.SilkS")
		)
		(fp_line
			(start -1.2954 0.5842)
			(end -1.2954 -0.5842)
			(stroke
				(width 0.1524)
				(type default)
			)
			(layer "F.SilkS")
		)
		(fp_line
			(start 1.2954 -0.5842)
			(end 1.2954 0.5842)
			(stroke
				(width 0.1524)
				(type default)
			)
			(layer "F.SilkS")
		)
		(fp_line
			(start 1.2954 0.5842)
			(end -1.2954 0.5842)
			(stroke
				(width 0.1524)
				(type default)
			)
			(layer "F.SilkS")
		)
		(fp_line
			(start -1.1938 -0.4064)
			(end -0.8636 -0.4064)
			(stroke
				(width 0.1)
				(type default)
			)
			(layer "F.Fab")
		)
		(fp_line
			(start -1.1938 0.4064)
			(end -1.1938 -0.4064)
			(stroke
				(width 0.1)
				(type default)
			)
			(layer "F.Fab")
		)
		(fp_line
			(start -0.8636 -0.4572)
			(end 0.8636 -0.4572)
			(stroke
				(width 0.1)
				(type default)
			)
			(layer "F.Fab")
		)
		(fp_line
			(start -0.8636 -0.4064)
			(end -0.8636 -0.4572)
			(stroke
				(width 0.1)
				(type default)
			)
			(layer "F.Fab")
		)
		(fp_line
			(start -0.8636 0.4064)
			(end -1.1938 0.4064)
			(stroke
				(width 0.1)
				(type default)
			)
			(layer "F.Fab")
		)
		(fp_line
			(start -0.8636 0.4572)
			(end -0.8636 0.4064)
			(stroke
				(width 0.1)
				(type default)
			)
			(layer "F.Fab")
		)
		(fp_line
			(start 0.8636 -0.4572)
			(end 0.8636 -0.4064)
			(stroke
				(width 0.1)
				(type default)
			)
			(layer "F.Fab")
		)
		(fp_line
			(start 0.8636 -0.4064)
			(end 1.1938 -0.4064)
			(stroke
				(width 0.1)
				(type default)
			)
			(layer "F.Fab")
		)
		(fp_line
			(start 0.8636 0.4064)
			(end 0.8636 0.4572)
			(stroke
				(width 0.1)
				(type default)
			)
			(layer "F.Fab")
		)
		(fp_line
			(start 0.8636 0.4572)
			(end -0.8636 0.4572)
			(stroke
				(width 0.1)
				(type default)
			)
			(layer "F.Fab")
		)
		(fp_line
			(start 1.1938 -0.4064)
			(end 1.1938 0.4064)
			(stroke
				(width 0.1)
				(type default)
			)
			(layer "F.Fab")
		)
		(fp_line
			(start 1.1938 0.4064)
			(end 0.8636 0.4064)
			(stroke
				(width 0.1)
				(type default)
			)
			(layer "F.Fab")
		)
		(pad "1" smd rect
			(at -0.7366 0 270)
			(size 0.7112 0.8128)
			(layers "F.Cu" "F.Mask" "F.Paste")
			(net "PCEPLL6_VDDA18_PEX0")
		)
		(pad "2" smd rect
			(at 0.7366 0 270)
			(size 0.7112 0.8128)
			(layers "F.Cu" "F.Mask" "F.Paste")
			(net "GND")
		)
	)
	(footprint ""
		(layer "F.Cu")
		(at 154.707844 -163.061396 180)
		(property "Reference" "R106"
			(at 0 0 180)
			(layer "F.SilkS")
			(hide yes)
			(effects
				(font
					(size 1.27 1.27)
				)
			)
		)
		(property "Value" ""
			(at 0 0 180)
			(layer "F.Fab")
			(effects
				(font
					(size 1.27 1.27)
				)
			)
		)
		(duplicate_pad_numbers_are_jumpers no)
		(fp_line
			(start 0.7874 0.4064)
			(end -0.7874 0.4064)
			(stroke
				(width 0.1524)
				(type default)
			)
			(layer "F.SilkS")
		)
		(fp_line
			(start 0.7874 -0.4064)
			(end 0.7874 0.4064)
			(stroke
				(width 0.1524)
				(type default)
			)
			(layer "F.SilkS")
		)
		(fp_line
			(start -0.7874 0.4064)
			(end -0.7874 -0.4064)
			(stroke
				(width 0.1524)
				(type default)
			)
			(layer "F.SilkS")
		)
		(fp_line
			(start -0.7874 -0.4064)
			(end 0.7874 -0.4064)
			(stroke
				(width 0.1524)
				(type default)
			)
			(layer "F.SilkS")
		)
		(fp_line
			(start 0.67945 0.3048)
			(end 0.120396 0.3048)
			(stroke
				(width 0.1)
				(type default)
			)
			(layer "F.Fab")
		)
		(fp_line
			(start 0.67945 -0.3048)
			(end 0.67945 0.3048)
			(stroke
				(width 0.1)
				(type default)
			)
			(layer "F.Fab")
		)
		(fp_line
			(start 0.12065 -0.2794)
			(end 0.12065 -0.3048)
			(stroke
				(width 0.1)
				(type default)
			)
			(layer "F.Fab")
		)
		(fp_line
			(start 0.12065 -0.3048)
			(end 0.67945 -0.3048)
			(stroke
				(width 0.1)
				(type default)
			)
			(layer "F.Fab")
		)
		(fp_line
			(start 0.120396 0.3048)
			(end 0.120396 0.2794)
			(stroke
				(width 0.1)
				(type default)
			)
			(layer "F.Fab")
		)
		(fp_line
			(start 0.120396 0.2794)
			(end -0.12065 0.2794)
			(stroke
				(width 0.1)
				(type default)
			)
			(layer "F.Fab")
		)
		(fp_line
			(start -0.12065 0.3048)
			(end -0.67945 0.3048)
			(stroke
				(width 0.1)
				(type default)
			)
			(layer "F.Fab")
		)
		(fp_line
			(start -0.12065 0.2794)
			(end -0.12065 0.3048)
			(stroke
				(width 0.1)
				(type default)
			)
			(layer "F.Fab")
		)
		(fp_line
			(start -0.12065 -0.2794)
			(end 0.12065 -0.2794)
			(stroke
				(width 0.1)
				(type default)
			)
			(layer "F.Fab")
		)
		(fp_line
			(start -0.12065 -0.305054)
			(end -0.12065 -0.2794)
			(stroke
				(width 0.1)
				(type default)
			)
			(layer "F.Fab")
		)
		(fp_line
			(start -0.67945 0.3048)
			(end -0.67945 -0.305054)
			(stroke
				(width 0.1)
				(type default)
			)
			(layer "F.Fab")
		)
		(fp_line
			(start -0.67945 -0.305054)
			(end -0.12065 -0.305054)
			(stroke
				(width 0.1)
				(type default)
			)
			(layer "F.Fab")
		)
		(pad "1" smd circle
			(at -0.40005 0 180)
			(size 0 0)
			(layers "F.Cu" "F.Mask" "F.Paste")
			(net "PWRGD_NIC2_PWR_GOOD")
		)
		(pad "2" smd circle
			(at 0.40005 0 180)
			(size 0 0)
			(layers "F.Cu" "F.Mask" "F.Paste")
			(net "PWRGD_NIC2_PWR_GOOD_R")
		)
	)
	(footprint ""
		(layer "F.Cu")
		(at 227.566982 -155.998672 -90)
		(property "Reference" "R4209"
			(at 0 0 270)
			(layer "F.SilkS")
			(hide yes)
			(effects
				(font
					(size 1.27 1.27)
				)
			)
		)
		(property "Value" ""
			(at 0 0 270)
			(layer "F.Fab")
			(effects
				(font
					(size 1.27 1.27)
				)
			)
		)
		(duplicate_pad_numbers_are_jumpers no)
		(fp_line
			(start -0.7874 0.4064)
			(end -0.7874 -0.4064)
			(stroke
				(width 0.1524)
				(type default)
			)
			(layer "F.SilkS")
		)
		(fp_line
			(start 0.7874 0.4064)
			(end -0.7874 0.4064)
			(stroke
				(width 0.1524)
				(type default)
			)
			(layer "F.SilkS")
		)
		(fp_line
			(start -0.7874 -0.4064)
			(end 0.7874 -0.4064)
			(stroke
				(width 0.1524)
				(type default)
			)
			(layer "F.SilkS")
		)
		(fp_line
			(start 0.7874 -0.4064)
			(end 0.7874 0.4064)
			(stroke
				(width 0.1524)
				(type default)
			)
			(layer "F.SilkS")
		)
		(fp_line
			(start -0.67945 0.3048)
			(end -0.67945 -0.305054)
			(stroke
				(width 0.1)
				(type default)
			)
			(layer "F.Fab")
		)
		(fp_line
			(start -0.12065 0.3048)
			(end -0.67945 0.3048)
			(stroke
				(width 0.1)
				(type default)
			)
			(layer "F.Fab")
		)
		(fp_line
			(start 0.120396 0.3048)
			(end 0.120396 0.2794)
			(stroke
				(width 0.1)
				(type default)
			)
			(layer "F.Fab")
		)
		(fp_line
			(start 0.67945 0.3048)
			(end 0.120396 0.3048)
			(stroke
				(width 0.1)
				(type default)
			)
			(layer "F.Fab")
		)
		(fp_line
			(start -0.12065 0.2794)
			(end -0.12065 0.3048)
			(stroke
				(width 0.1)
				(type default)
			)
			(layer "F.Fab")
		)
		(fp_line
			(start 0.120396 0.2794)
			(end -0.12065 0.2794)
			(stroke
				(width 0.1)
				(type default)
			)
			(layer "F.Fab")
		)
		(fp_line
			(start -0.12065 -0.2794)
			(end 0.12065 -0.2794)
			(stroke
				(width 0.1)
				(type default)
			)
			(layer "F.Fab")
		)
		(fp_line
			(start 0.12065 -0.2794)
			(end 0.12065 -0.3048)
			(stroke
				(width 0.1)
				(type default)
			)
			(layer "F.Fab")
		)
		(fp_line
			(start 0.12065 -0.3048)
			(end 0.67945 -0.3048)
			(stroke
				(width 0.1)
				(type default)
			)
			(layer "F.Fab")
		)
		(fp_line
			(start 0.67945 -0.3048)
			(end 0.67945 0.3048)
			(stroke
				(width 0.1)
				(type default)
			)
			(layer "F.Fab")
		)
		(fp_line
			(start -0.67945 -0.305054)
			(end -0.12065 -0.305054)
			(stroke
				(width 0.1)
				(type default)
			)
			(layer "F.Fab")
		)
		(fp_line
			(start -0.12065 -0.305054)
			(end -0.12065 -0.2794)
			(stroke
				(width 0.1)
				(type default)
			)
			(layer "F.Fab")
		)
		(pad "1" smd circle
			(at -0.40005 0 270)
			(size 0 0)
			(layers "F.Cu" "F.Mask" "F.Paste")
			(net "GND")
		)
		(pad "2" smd circle
			(at 0.40005 0 270)
			(size 0 0)
			(layers "F.Cu" "F.Mask" "F.Paste")
			(net "PEX_REF_CLK_GEN_EN_N")
		)
	)
	(footprint ""
		(layer "F.Cu")
		(at 353.822 -177.546)
		(property "Reference" "R4757"
			(at 0 0 0)
			(layer "F.SilkS")
			(hide yes)
			(effects
				(font
					(size 1.27 1.27)
				)
			)
		)
		(property "Value" ""
			(at 0 0 0)
			(layer "F.Fab")
			(effects
				(font
					(size 1.27 1.27)
				)
			)
		)
		(duplicate_pad_numbers_are_jumpers no)
		(fp_line
			(start -0.7874 -0.4064)
			(end 0.7874 -0.4064)
			(stroke
				(width 0.1524)
				(type default)
			)
			(layer "F.SilkS")
		)
		(fp_line
			(start -0.7874 0.4064)
			(end -0.7874 -0.4064)
			(stroke
				(width 0.1524)
				(type default)
			)
			(layer "F.SilkS")
		)
		(fp_line
			(start 0.7874 -0.4064)
			(end 0.7874 0.4064)
			(stroke
				(width 0.1524)
				(type default)
			)
			(layer "F.SilkS")
		)
		(fp_line
			(start 0.7874 0.4064)
			(end -0.7874 0.4064)
			(stroke
				(width 0.1524)
				(type default)
			)
			(layer "F.SilkS")
		)
		(fp_line
			(start -0.67945 -0.305054)
			(end -0.12065 -0.305054)
			(stroke
				(width 0.1)
				(type default)
			)
			(layer "F.Fab")
		)
		(fp_line
			(start -0.67945 0.3048)
			(end -0.67945 -0.305054)
			(stroke
				(width 0.1)
				(type default)
			)
			(layer "F.Fab")
		)
		(fp_line
			(start -0.12065 -0.305054)
			(end -0.12065 -0.2794)
			(stroke
				(width 0.1)
				(type default)
			)
			(layer "F.Fab")
		)
		(fp_line
			(start -0.12065 -0.2794)
			(end 0.12065 -0.2794)
			(stroke
				(width 0.1)
				(type default)
			)
			(layer "F.Fab")
		)
		(fp_line
			(start -0.12065 0.2794)
			(end -0.12065 0.3048)
			(stroke
				(width 0.1)
				(type default)
			)
			(layer "F.Fab")
		)
		(fp_line
			(start -0.12065 0.3048)
			(end -0.67945 0.3048)
			(stroke
				(width 0.1)
				(type default)
			)
			(layer "F.Fab")
		)
		(fp_line
			(start 0.120396 0.2794)
			(end -0.12065 0.2794)
			(stroke
				(width 0.1)
				(type default)
			)
			(layer "F.Fab")
		)
		(fp_line
			(start 0.120396 0.3048)
			(end 0.120396 0.2794)
			(stroke
				(width 0.1)
				(type default)
			)
			(layer "F.Fab")
		)
		(fp_line
			(start 0.12065 -0.3048)
			(end 0.67945 -0.3048)
			(stroke
				(width 0.1)
				(type default)
			)
			(layer "F.Fab")
		)
		(fp_line
			(start 0.12065 -0.2794)
			(end 0.12065 -0.3048)
			(stroke
				(width 0.1)
				(type default)
			)
			(layer "F.Fab")
		)
		(fp_line
			(start 0.67945 -0.3048)
			(end 0.67945 0.3048)
			(stroke
				(width 0.1)
				(type default)
			)
			(layer "F.Fab")
		)
		(fp_line
			(start 0.67945 0.3048)
			(end 0.120396 0.3048)
			(stroke
				(width 0.1)
				(type default)
			)
			(layer "F.Fab")
		)
		(pad "1" smd circle
			(at -0.40005 0)
			(size 0 0)
			(layers "F.Cu" "F.Mask" "F.Paste")
			(net "PRSNT_NIC4_FPGA_PCA9555_N")
		)
		(pad "2" smd circle
			(at 0.40005 0)
			(size 0 0)
			(layers "F.Cu" "F.Mask" "F.Paste")
			(net "PRSNT_NIC4_FPGA_R_N")
		)
	)
	(footprint ""
		(layer "F.Cu")
		(at 219.457778 -257.975862 -90)
		(property "Reference" "R6504"
			(at 0 0 270)
			(layer "F.SilkS")
			(hide yes)
			(effects
				(font
					(size 1.27 1.27)
				)
			)
		)
		(property "Value" ""
			(at 0 0 270)
			(layer "F.Fab")
			(effects
				(font
					(size 1.27 1.27)
				)
			)
		)
		(duplicate_pad_numbers_are_jumpers no)
		(fp_line
			(start -0.7874 0.4064)
			(end -0.7874 -0.4064)
			(stroke
				(width 0.1524)
				(type default)
			)
			(layer "F.SilkS")
		)
		(fp_line
			(start 0.7874 0.4064)
			(end -0.7874 0.4064)
			(stroke
				(width 0.1524)
				(type default)
			)
			(layer "F.SilkS")
		)
		(fp_line
			(start -0.7874 -0.4064)
			(end 0.7874 -0.4064)
			(stroke
				(width 0.1524)
				(type default)
			)
			(layer "F.SilkS")
		)
		(fp_line
			(start 0.7874 -0.4064)
			(end 0.7874 0.4064)
			(stroke
				(width 0.1524)
				(type default)
			)
			(layer "F.SilkS")
		)
		(fp_line
			(start -0.67945 0.3048)
			(end -0.67945 -0.305054)
			(stroke
				(width 0.1)
				(type default)
			)
			(layer "F.Fab")
		)
		(fp_line
			(start -0.12065 0.3048)
			(end -0.67945 0.3048)
			(stroke
				(width 0.1)
				(type default)
			)
			(layer "F.Fab")
		)
		(fp_line
			(start 0.120396 0.3048)
			(end 0.120396 0.2794)
			(stroke
				(width 0.1)
				(type default)
			)
			(layer "F.Fab")
		)
		(fp_line
			(start 0.67945 0.3048)
			(end 0.120396 0.3048)
			(stroke
				(width 0.1)
				(type default)
			)
			(layer "F.Fab")
		)
		(fp_line
			(start -0.12065 0.2794)
			(end -0.12065 0.3048)
			(stroke
				(width 0.1)
				(type default)
			)
			(layer "F.Fab")
		)
		(fp_line
			(start 0.120396 0.2794)
			(end -0.12065 0.2794)
			(stroke
				(width 0.1)
				(type default)
			)
			(layer "F.Fab")
		)
		(fp_line
			(start -0.12065 -0.2794)
			(end 0.12065 -0.2794)
			(stroke
				(width 0.1)
				(type default)
			)
			(layer "F.Fab")
		)
		(fp_line
			(start 0.12065 -0.2794)
			(end 0.12065 -0.3048)
			(stroke
				(width 0.1)
				(type default)
			)
			(layer "F.Fab")
		)
		(fp_line
			(start 0.12065 -0.3048)
			(end 0.67945 -0.3048)
			(stroke
				(width 0.1)
				(type default)
			)
			(layer "F.Fab")
		)
		(fp_line
			(start 0.67945 -0.3048)
			(end 0.67945 0.3048)
			(stroke
				(width 0.1)
				(type default)
			)
			(layer "F.Fab")
		)
		(fp_line
			(start -0.67945 -0.305054)
			(end -0.12065 -0.305054)
			(stroke
				(width 0.1)
				(type default)
			)
			(layer "F.Fab")
		)
		(fp_line
			(start -0.12065 -0.305054)
			(end -0.12065 -0.2794)
			(stroke
				(width 0.1)
				(type default)
			)
			(layer "F.Fab")
		)
		(pad "1" smd circle
			(at -0.40005 0 270)
			(size 0 0)
			(layers "F.Cu" "F.Mask" "F.Paste")
			(net "P1V25_SERDES_VDDPLL_PEX1")
		)
		(pad "2" smd circle
			(at 0.40005 0 270)
			(size 0 0)
			(layers "F.Cu" "F.Mask" "F.Paste")
			(net "P1V25_SERDES_VDDPLL_PEX1_C11")
		)
	)
	(footprint ""
		(layer "F.Cu")
		(at 457.436982 -116.230654 90)
		(property "Reference" "R5969"
			(at 0 0 90)
			(layer "F.SilkS")
			(hide yes)
			(effects
				(font
					(size 1.27 1.27)
				)
			)
		)
		(property "Value" ""
			(at 0 0 90)
			(layer "F.Fab")
			(effects
				(font
					(size 1.27 1.27)
				)
			)
		)
		(duplicate_pad_numbers_are_jumpers no)
		(fp_line
			(start 0.7874 -0.4064)
			(end 0.7874 0.4064)
			(stroke
				(width 0.1524)
				(type default)
			)
			(layer "F.SilkS")
		)
		(fp_line
			(start -0.7874 -0.4064)
			(end 0.7874 -0.4064)
			(stroke
				(width 0.1524)
				(type default)
			)
			(layer "F.SilkS")
		)
		(fp_line
			(start 0.7874 0.4064)
			(end -0.7874 0.4064)
			(stroke
				(width 0.1524)
				(type default)
			)
			(layer "F.SilkS")
		)
		(fp_line
			(start -0.7874 0.4064)
			(end -0.7874 -0.4064)
			(stroke
				(width 0.1524)
				(type default)
			)
			(layer "F.SilkS")
		)
		(fp_line
			(start -0.12065 -0.305054)
			(end -0.12065 -0.2794)
			(stroke
				(width 0.1)
				(type default)
			)
			(layer "F.Fab")
		)
		(fp_line
			(start -0.67945 -0.305054)
			(end -0.12065 -0.305054)
			(stroke
				(width 0.1)
				(type default)
			)
			(layer "F.Fab")
		)
		(fp_line
			(start 0.67945 -0.3048)
			(end 0.67945 0.3048)
			(stroke
				(width 0.1)
				(type default)
			)
			(layer "F.Fab")
		)
		(fp_line
			(start 0.12065 -0.3048)
			(end 0.67945 -0.3048)
			(stroke
				(width 0.1)
				(type default)
			)
			(layer "F.Fab")
		)
		(fp_line
			(start 0.12065 -0.2794)
			(end 0.12065 -0.3048)
			(stroke
				(width 0.1)
				(type default)
			)
			(layer "F.Fab")
		)
		(fp_line
			(start -0.12065 -0.2794)
			(end 0.12065 -0.2794)
			(stroke
				(width 0.1)
				(type default)
			)
			(layer "F.Fab")
		)
		(fp_line
			(start 0.120396 0.2794)
			(end -0.12065 0.2794)
			(stroke
				(width 0.1)
				(type default)
			)
			(layer "F.Fab")
		)
		(fp_line
			(start -0.12065 0.2794)
			(end -0.12065 0.3048)
			(stroke
				(width 0.1)
				(type default)
			)
			(layer "F.Fab")
		)
		(fp_line
			(start 0.67945 0.3048)
			(end 0.120396 0.3048)
			(stroke
				(width 0.1)
				(type default)
			)
			(layer "F.Fab")
		)
		(fp_line
			(start 0.120396 0.3048)
			(end 0.120396 0.2794)
			(stroke
				(width 0.1)
				(type default)
			)
			(layer "F.Fab")
		)
		(fp_line
			(start -0.12065 0.3048)
			(end -0.67945 0.3048)
			(stroke
				(width 0.1)
				(type default)
			)
			(layer "F.Fab")
		)
		(fp_line
			(start -0.67945 0.3048)
			(end -0.67945 -0.305054)
			(stroke
				(width 0.1)
				(type default)
			)
			(layer "F.Fab")
		)
		(pad "1" smd circle
			(at -0.40005 0 90)
			(size 0 0)
			(layers "F.Cu" "F.Mask" "F.Paste")
			(net "PWRGD_P12V_NIC7_CO")
		)
		(pad "2" smd circle
			(at 0.40005 0 90)
			(size 0 0)
			(layers "F.Cu" "F.Mask" "F.Paste")
			(net "PWRGD_P12V_NIC7_R")
		)
	)
)
